(kicad_pcb
	(version 20260206)
	(generator "pcbnew")
	(generator_version "10.0")
	(general
		(thickness 1.6)
		(legacy_teardrops no)
	)
	(paper "A4")
	(title_block
		(title "03242023_DA0F0TMBIJ0_F0T_Motherboard_J_brd_V01_OCP.brd")
		(comment 1 "Grand Teton / footprints 2900-2903 of 6105")
	)
	(layers
		(0 "F.Cu" signal "TOP")
		(4 "In1.Cu" signal "GND")
		(6 "In2.Cu" signal "IN1")
		(8 "In3.Cu" signal "GND1")
		(10 "In4.Cu" signal "IN2")
		(12 "In5.Cu" signal "GND2")
		(14 "In6.Cu" signal "IN3")
		(16 "In7.Cu" signal "GND3")
		(18 "In8.Cu" signal "VCC")
		(20 "In9.Cu" signal "VCC1")
		(22 "In10.Cu" signal "GND4")
		(24 "In11.Cu" signal "IN4")
		(26 "In12.Cu" signal "GND5")
		(28 "In13.Cu" signal "IN5")
		(30 "In14.Cu" signal "GND6")
		(32 "In15.Cu" signal "IN6")
		(34 "In16.Cu" signal "GND7")
		(2 "B.Cu" signal "BOTTOM")
		(9 "F.Adhes" user "F.Adhesive")
		(11 "B.Adhes" user "B.Adhesive")
		(13 "F.Paste" user "Package Geometry/Pastemask Top")
		(15 "B.Paste" user "Package Geometry/Pastemask Bottom")
		(5 "F.SilkS" user "Ref Des/Silkscreen Top")
		(7 "B.SilkS" user "Ref Des/Silkscreen Bottom")
		(1 "F.Mask" user "Board Geometry/Soldermask Top")
		(3 "B.Mask" user "Board Geometry/Soldermask Bottom")
		(17 "Dwgs.User" user "User.Drawings")
		(19 "Cmts.User" user "User.Comments")
		(21 "Eco1.User" user "User.Eco1")
		(23 "Eco2.User" user "User.Eco2")
		(25 "Edge.Cuts" user "Board Geometry/Outline")
		(27 "Margin" user)
		(31 "F.CrtYd" user "Package Geometry/Place Bound Top")
		(29 "B.CrtYd" user "Package Geometry/Place Bound Bottom")
		(35 "F.Fab" user "Ref Des/Assembly Top")
		(33 "B.Fab" user "Ref Des/Assembly Bottom")
	)
	(footprint ""
		(layer "F.Cu")
		(at 376.488198 -359.871518 -90)
		(property "Reference" "PC2643"
			(at 0 0 270)
			(layer "F.SilkS")
			(hide yes)
			(effects
				(font
					(size 1.27 1.27)
				)
			)
		)
		(property "Value" ""
			(at 0 0 270)
			(layer "F.Fab")
			(effects
				(font
					(size 1.27 1.27)
				)
			)
		)
		(duplicate_pad_numbers_are_jumpers no)
		(fp_line
			(start -0.7874 0.4064)
			(end -0.7874 -0.4064)
			(stroke
				(width 0.1524)
				(type default)
			)
			(layer "F.SilkS")
		)
		(fp_line
			(start 0.7874 0.4064)
			(end -0.7874 0.4064)
			(stroke
				(width 0.1524)
				(type default)
			)
			(layer "F.SilkS")
		)
		(fp_line
			(start -0.7874 -0.4064)
			(end 0.7874 -0.4064)
			(stroke
				(width 0.1524)
				(type default)
			)
			(layer "F.SilkS")
		)
		(fp_line
			(start 0.7874 -0.4064)
			(end 0.7874 0.4064)
			(stroke
				(width 0.1524)
				(type default)
			)
			(layer "F.SilkS")
		)
		(fp_line
			(start -0.67945 0.3048)
			(end -0.67945 -0.305054)
			(stroke
				(width 0.1)
				(type default)
			)
			(layer "F.Fab")
		)
		(fp_line
			(start -0.12065 0.3048)
			(end -0.67945 0.3048)
			(stroke
				(width 0.1)
				(type default)
			)
			(layer "F.Fab")
		)
		(fp_line
			(start 0.120396 0.3048)
			(end 0.120396 0.2794)
			(stroke
				(width 0.1)
				(type default)
			)
			(layer "F.Fab")
		)
		(fp_line
			(start 0.67945 0.3048)
			(end 0.120396 0.3048)
			(stroke
				(width 0.1)
				(type default)
			)
			(layer "F.Fab")
		)
		(fp_line
			(start -0.12065 0.2794)
			(end -0.12065 0.3048)
			(stroke
				(width 0.1)
				(type default)
			)
			(layer "F.Fab")
		)
		(fp_line
			(start 0.120396 0.2794)
			(end -0.12065 0.2794)
			(stroke
				(width 0.1)
				(type default)
			)
			(layer "F.Fab")
		)
		(fp_line
			(start -0.12065 -0.2794)
			(end 0.12065 -0.2794)
			(stroke
				(width 0.1)
				(type default)
			)
			(layer "F.Fab")
		)
		(fp_line
			(start 0.12065 -0.2794)
			(end 0.12065 -0.3048)
			(stroke
				(width 0.1)
				(type default)
			)
			(layer "F.Fab")
		)
		(fp_line
			(start 0.12065 -0.3048)
			(end 0.67945 -0.3048)
			(stroke
				(width 0.1)
				(type default)
			)
			(layer "F.Fab")
		)
		(fp_line
			(start 0.67945 -0.3048)
			(end 0.67945 0.3048)
			(stroke
				(width 0.1)
				(type default)
			)
			(layer "F.Fab")
		)
		(fp_line
			(start -0.67945 -0.305054)
			(end -0.12065 -0.305054)
			(stroke
				(width 0.1)
				(type default)
			)
			(layer "F.Fab")
		)
		(fp_line
			(start -0.12065 -0.305054)
			(end -0.12065 -0.2794)
			(stroke
				(width 0.1)
				(type default)
			)
			(layer "F.Fab")
		)
		(pad "1" smd circle
			(at -0.40005 0 270)
			(size 0 0)
			(layers "F.Cu" "F.Mask" "F.Paste")
			(net "PVPP_HBM_CPU0_VCC")
		)
		(pad "2" smd circle
			(at 0.40005 0 270)
			(size 0 0)
			(layers "F.Cu" "F.Mask" "F.Paste")
			(net "GND")
		)
	)
	(footprint ""
		(layer "F.Cu")
		(at 175.883062 -23.283672 180)
		(property "Reference" "PR4006"
			(at 0 0 180)
			(layer "F.SilkS")
			(hide yes)
			(effects
				(font
					(size 1.27 1.27)
				)
			)
		)
		(property "Value" ""
			(at 0 0 180)
			(layer "F.Fab")
			(effects
				(font
					(size 1.27 1.27)
				)
			)
		)
		(duplicate_pad_numbers_are_jumpers no)
		(fp_line
			(start 0.7874 0.4064)
			(end -0.7874 0.4064)
			(stroke
				(width 0.1524)
				(type default)
			)
			(layer "F.SilkS")
		)
		(fp_line
			(start 0.7874 -0.4064)
			(end 0.7874 0.4064)
			(stroke
				(width 0.1524)
				(type default)
			)
			(layer "F.SilkS")
		)
		(fp_line
			(start -0.7874 0.4064)
			(end -0.7874 -0.4064)
			(stroke
				(width 0.1524)
				(type default)
			)
			(layer "F.SilkS")
		)
		(fp_line
			(start -0.7874 -0.4064)
			(end 0.7874 -0.4064)
			(stroke
				(width 0.1524)
				(type default)
			)
			(layer "F.SilkS")
		)
		(fp_line
			(start 0.67945 0.3048)
			(end 0.120396 0.3048)
			(stroke
				(width 0.1)
				(type default)
			)
			(layer "F.Fab")
		)
		(fp_line
			(start 0.67945 -0.3048)
			(end 0.67945 0.3048)
			(stroke
				(width 0.1)
				(type default)
			)
			(layer "F.Fab")
		)
		(fp_line
			(start 0.12065 -0.2794)
			(end 0.12065 -0.3048)
			(stroke
				(width 0.1)
				(type default)
			)
			(layer "F.Fab")
		)
		(fp_line
			(start 0.12065 -0.3048)
			(end 0.67945 -0.3048)
			(stroke
				(width 0.1)
				(type default)
			)
			(layer "F.Fab")
		)
		(fp_line
			(start 0.120396 0.3048)
			(end 0.120396 0.2794)
			(stroke
				(width 0.1)
				(type default)
			)
			(layer "F.Fab")
		)
		(fp_line
			(start 0.120396 0.2794)
			(end -0.12065 0.2794)
			(stroke
				(width 0.1)
				(type default)
			)
			(layer "F.Fab")
		)
		(fp_line
			(start -0.12065 0.3048)
			(end -0.67945 0.3048)
			(stroke
				(width 0.1)
				(type default)
			)
			(layer "F.Fab")
		)
		(fp_line
			(start -0.12065 0.2794)
			(end -0.12065 0.3048)
			(stroke
				(width 0.1)
				(type default)
			)
			(layer "F.Fab")
		)
		(fp_line
			(start -0.12065 -0.2794)
			(end 0.12065 -0.2794)
			(stroke
				(width 0.1)
				(type default)
			)
			(layer "F.Fab")
		)
		(fp_line
			(start -0.12065 -0.305054)
			(end -0.12065 -0.2794)
			(stroke
				(width 0.1)
				(type default)
			)
			(layer "F.Fab")
		)
		(fp_line
			(start -0.67945 0.3048)
			(end -0.67945 -0.305054)
			(stroke
				(width 0.1)
				(type default)
			)
			(layer "F.Fab")
		)
		(fp_line
			(start -0.67945 -0.305054)
			(end -0.12065 -0.305054)
			(stroke
				(width 0.1)
				(type default)
			)
			(layer "F.Fab")
		)
		(pad "1" smd circle
			(at -0.40005 0 180)
			(size 0 0)
			(layers "F.Cu" "F.Mask" "F.Paste")
			(net "P12V_SCM_R")
		)
		(pad "2" smd circle
			(at 0.40005 0 180)
			(size 0 0)
			(layers "F.Cu" "F.Mask" "F.Paste")
			(net "P12V_SCM_AVIN_PD")
		)
	)
	(footprint ""
		(layer "F.Cu")
		(at 465.821014 -117.651022 180)
		(property "Reference" "R1130"
			(at 0 0 180)
			(layer "F.SilkS")
			(hide yes)
			(effects
				(font
					(size 1.27 1.27)
				)
			)
		)
		(property "Value" ""
			(at 0 0 180)
			(layer "F.Fab")
			(effects
				(font
					(size 1.27 1.27)
				)
			)
		)
		(duplicate_pad_numbers_are_jumpers no)
		(fp_line
			(start 0.7874 0.4064)
			(end -0.7874 0.4064)
			(stroke
				(width 0.1524)
				(type default)
			)
			(layer "F.SilkS")
		)
		(fp_line
			(start 0.7874 -0.4064)
			(end 0.7874 0.4064)
			(stroke
				(width 0.1524)
				(type default)
			)
			(layer "F.SilkS")
		)
		(fp_line
			(start -0.7874 0.4064)
			(end -0.7874 -0.4064)
			(stroke
				(width 0.1524)
				(type default)
			)
			(layer "F.SilkS")
		)
		(fp_line
			(start -0.7874 -0.4064)
			(end 0.7874 -0.4064)
			(stroke
				(width 0.1524)
				(type default)
			)
			(layer "F.SilkS")
		)
		(fp_line
			(start 0.67945 0.3048)
			(end 0.120396 0.3048)
			(stroke
				(width 0.1)
				(type default)
			)
			(layer "F.Fab")
		)
		(fp_line
			(start 0.67945 -0.3048)
			(end 0.67945 0.3048)
			(stroke
				(width 0.1)
				(type default)
			)
			(layer "F.Fab")
		)
		(fp_line
			(start 0.12065 -0.2794)
			(end 0.12065 -0.3048)
			(stroke
				(width 0.1)
				(type default)
			)
			(layer "F.Fab")
		)
		(fp_line
			(start 0.12065 -0.3048)
			(end 0.67945 -0.3048)
			(stroke
				(width 0.1)
				(type default)
			)
			(layer "F.Fab")
		)
		(fp_line
			(start 0.120396 0.3048)
			(end 0.120396 0.2794)
			(stroke
				(width 0.1)
				(type default)
			)
			(layer "F.Fab")
		)
		(fp_line
			(start 0.120396 0.2794)
			(end -0.12065 0.2794)
			(stroke
				(width 0.1)
				(type default)
			)
			(layer "F.Fab")
		)
		(fp_line
			(start -0.12065 0.3048)
			(end -0.67945 0.3048)
			(stroke
				(width 0.1)
				(type default)
			)
			(layer "F.Fab")
		)
		(fp_line
			(start -0.12065 0.2794)
			(end -0.12065 0.3048)
			(stroke
				(width 0.1)
				(type default)
			)
			(layer "F.Fab")
		)
		(fp_line
			(start -0.12065 -0.2794)
			(end 0.12065 -0.2794)
			(stroke
				(width 0.1)
				(type default)
			)
			(layer "F.Fab")
		)
		(fp_line
			(start -0.12065 -0.305054)
			(end -0.12065 -0.2794)
			(stroke
				(width 0.1)
				(type default)
			)
			(layer "F.Fab")
		)
		(fp_line
			(start -0.67945 0.3048)
			(end -0.67945 -0.305054)
			(stroke
				(width 0.1)
				(type default)
			)
			(layer "F.Fab")
		)
		(fp_line
			(start -0.67945 -0.305054)
			(end -0.12065 -0.305054)
			(stroke
				(width 0.1)
				(type default)
			)
			(layer "F.Fab")
		)
		(pad "1" smd circle
			(at -0.40005 0 180)
			(size 0 0)
			(layers "F.Cu" "F.Mask" "F.Paste")
			(net "SMB_PEHPCPU0_LVC3_SCL")
		)
		(pad "2" smd circle
			(at 0.40005 0 180)
			(size 0 0)
			(layers "F.Cu" "F.Mask" "F.Paste")
			(net "SMB_PEHPCPU0_LVC3_R_SCL")
		)
	)
	(footprint ""
		(layer "F.Cu")
		(at 298.13504 -409.69184)
		(property "Reference" "R4894"
			(at 0 0 0)
			(layer "F.SilkS")
			(hide yes)
			(effects
				(font
					(size 1.27 1.27)
				)
			)
		)
		(property "Value" ""
			(at 0 0 0)
			(layer "F.Fab")
			(effects
				(font
					(size 1.27 1.27)
				)
			)
		)
		(duplicate_pad_numbers_are_jumpers no)
		(fp_line
			(start -0.7874 -0.4064)
			(end 0.7874 -0.4064)
			(stroke
				(width 0.1524)
				(type default)
			)
			(layer "F.SilkS")
		)
		(fp_line
			(start -0.7874 0.4064)
			(end -0.7874 -0.4064)
			(stroke
				(width 0.1524)
				(type default)
			)
			(layer "F.SilkS")
		)
		(fp_line
			(start 0.7874 -0.4064)
			(end 0.7874 0.4064)
			(stroke
				(width 0.1524)
				(type default)
			)
			(layer "F.SilkS")
		)
		(fp_line
			(start 0.7874 0.4064)
			(end -0.7874 0.4064)
			(stroke
				(width 0.1524)
				(type default)
			)
			(layer "F.SilkS")
		)
		(fp_line
			(start -0.67945 -0.305054)
			(end -0.12065 -0.305054)
			(stroke
				(width 0.1)
				(type default)
			)
			(layer "F.Fab")
		)
		(fp_line
			(start -0.67945 0.3048)
			(end -0.67945 -0.305054)
			(stroke
				(width 0.1)
				(type default)
			)
			(layer "F.Fab")
		)
		(fp_line
			(start -0.12065 -0.305054)
			(end -0.12065 -0.2794)
			(stroke
				(width 0.1)
				(type default)
			)
			(layer "F.Fab")
		)
		(fp_line
			(start -0.12065 -0.2794)
			(end 0.12065 -0.2794)
			(stroke
				(width 0.1)
				(type default)
			)
			(layer "F.Fab")
		)
		(fp_line
			(start -0.12065 0.2794)
			(end -0.12065 0.3048)
			(stroke
				(width 0.1)
				(type default)
			)
			(layer "F.Fab")
		)
		(fp_line
			(start -0.12065 0.3048)
			(end -0.67945 0.3048)
			(stroke
				(width 0.1)
				(type default)
			)
			(layer "F.Fab")
		)
		(fp_line
			(start 0.120396 0.2794)
			(end -0.12065 0.2794)
			(stroke
				(width 0.1)
				(type default)
			)
			(layer "F.Fab")
		)
		(fp_line
			(start 0.120396 0.3048)
			(end 0.120396 0.2794)
			(stroke
				(width 0.1)
				(type default)
			)
			(layer "F.Fab")
		)
		(fp_line
			(start 0.12065 -0.3048)
			(end 0.67945 -0.3048)
			(stroke
				(width 0.1)
				(type default)
			)
			(layer "F.Fab")
		)
		(fp_line
			(start 0.12065 -0.2794)
			(end 0.12065 -0.3048)
			(stroke
				(width 0.1)
				(type default)
			)
			(layer "F.Fab")
		)
		(fp_line
			(start 0.67945 -0.3048)
			(end 0.67945 0.3048)
			(stroke
				(width 0.1)
				(type default)
			)
			(layer "F.Fab")
		)
		(fp_line
			(start 0.67945 0.3048)
			(end 0.120396 0.3048)
			(stroke
				(width 0.1)
				(type default)
			)
			(layer "F.Fab")
		)
		(pad "1" smd circle
			(at -0.40005 0)
			(size 0 0)
			(layers "F.Cu" "F.Mask" "F.Paste")
			(net "P12V_HSC_TEMP_SCL")
		)
		(pad "2" smd circle
			(at 0.40005 0)
			(size 0 0)
			(layers "F.Cu" "F.Mask" "F.Paste")
			(net "SMB_LM75_0_3V3AUX_SCL")
		)
	)
)
